(kicad_pcb
	(version 20260206)
	(generator "pcbnew")
	(generator_version "10.0")
	(general
		(thickness 1.6)
		(legacy_teardrops no)
	)
	(paper "A4")
	(title_block
		(title "baseboard — 13948-1b.1110WZS1818.brd")
		(comment 1 "Honey Badger (Wiwynn) / footprints 1689-1695 of 2523")
	)
	(layers
		(0 "F.Cu" signal "TOP")
		(4 "In1.Cu" signal "L2GND")
		(6 "In2.Cu" signal "L3")
		(8 "In3.Cu" signal "L4VCC")
		(10 "In4.Cu" signal "L5VCC")
		(12 "In5.Cu" signal "L6")
		(14 "In6.Cu" signal "L7GND")
		(2 "B.Cu" signal "BOTTOM")
		(9 "F.Adhes" user "F.Adhesive")
		(11 "B.Adhes" user "B.Adhesive")
		(13 "F.Paste" user "Package Geometry/Pastemask Top")
		(15 "B.Paste" user "Package Geometry/Pastemask Bottom")
		(5 "F.SilkS" user "Ref Des/Silkscreen Top")
		(7 "B.SilkS" user "Ref Des/Silkscreen Bottom")
		(1 "F.Mask" user "Board Geometry/Soldermask Top")
		(3 "B.Mask" user "Board Geometry/Soldermask Bottom")
		(17 "Dwgs.User" user "User.Drawings")
		(19 "Cmts.User" user "User.Comments")
		(21 "Eco1.User" user "User.Eco1")
		(23 "Eco2.User" user "User.Eco2")
		(25 "Edge.Cuts" user "Board Geometry/Outline")
		(27 "Margin" user)
		(31 "F.CrtYd" user "Package Geometry/Place Bound Top")
		(29 "B.CrtYd" user "Package Geometry/Place Bound Bottom")
		(35 "F.Fab" user "Ref Des/Assembly Top")
		(33 "B.Fab" user "Ref Des/Assembly Bottom")
	)
	(footprint ""
		(layer "F.Cu")
		(at 257.175 -132.08)
		(property "Reference" "U192"
			(at 0 0 0)
			(layer "F.SilkS")
			(hide yes)
			(effects
				(font
					(size 1.27 1.27)
				)
			)
		)
		(property "Value" "74HC2G125DP-GP"
			(at 0 -9.0932 0)
			(unlocked yes)
			(layer "F.Fab")
			(hide yes)
			(effects
				(font
					(size 1.016 1.016)
					(thickness 0.1524)
				)
			)
		)
		(property "Device Type" "SSOIC8H44"
			(at 0 -10.6172 0)
			(unlocked yes)
			(layer "F.Fab")
			(hide yes)
			(effects
				(font
					(size 1.016 1.016)
					(thickness 0.1524)
				)
			)
		)
		(duplicate_pad_numbers_are_jumpers no)
		(fp_line
			(start -1.7018 -0.5842)
			(end -1.7018 0.5842)
			(stroke
				(width 0.1524)
				(type default)
			)
			(layer "F.SilkS")
		)
		(fp_line
			(start -1.7018 -0.5842)
			(end 1.0668 -0.5842)
			(stroke
				(width 0.1524)
				(type default)
			)
			(layer "F.SilkS")
		)
		(fp_line
			(start -1.524 0.5842)
			(end -1.524 2.286)
			(stroke
				(width 0.508)
				(type default)
			)
			(layer "F.SilkS")
		)
		(fp_line
			(start -1.397 0)
			(end -1.7018 -0.3048)
			(stroke
				(width 0.1524)
				(type default)
			)
			(layer "F.SilkS")
		)
		(fp_line
			(start -1.397 0)
			(end -1.7018 0.3048)
			(stroke
				(width 0.1524)
				(type default)
			)
			(layer "F.SilkS")
		)
		(fp_line
			(start 1.0668 -0.5842)
			(end 1.0668 0.5842)
			(stroke
				(width 0.1524)
				(type default)
			)
			(layer "F.SilkS")
		)
		(fp_line
			(start 1.0668 0.5842)
			(end -1.7018 0.5842)
			(stroke
				(width 0.1524)
				(type default)
			)
			(layer "F.SilkS")
		)
		(fp_poly
			(pts
				(xy -1.1684 0.5842) (xy 1.0668 0.5842) (xy 1.0668 -0.5842) (xy -1.1684 -0.5842)
			)
			(stroke
				(width 0)
				(type default)
			)
			(fill yes)
			(layer "F.SilkS")
		)
		(fp_rect
			(start -1.778 2.54)
			(end 1.778 -2.54)
			(stroke
				(width 0)
				(type default)
			)
			(fill no)
			(layer "F.CrtYd")
		)
		(fp_poly
			(pts
				(xy -1.778 -2.54) (xy 1.778 -2.54) (xy 1.778 2.54) (xy -1.778 2.54)
			)
			(stroke
				(width 0)
				(type default)
			)
			(fill no)
			(layer "F.Fab")
		)
		(pad "1" smd rect
			(at -0.97536 1.6256)
			(size 0.3556 1.524)
			(layers "F.Cu" "F.Mask" "F.Paste")
			(net "DEBUG_OE_1_N")
		)
		(pad "2" smd rect
			(at -0.32512 1.6256)
			(size 0.3556 1.524)
			(layers "F.Cu" "F.Mask" "F.Paste")
			(net "CPU_U192_PIN2_TX")
		)
		(pad "3" smd rect
			(at 0.32512 1.6256)
			(size 0.3556 1.524)
			(layers "F.Cu" "F.Mask" "F.Paste")
			(net "CPU_U192_PIN3_RX")
		)
		(pad "4" smd rect
			(at 0.97536 1.6256)
			(size 0.3556 1.524)
			(layers "F.Cu" "F.Mask" "F.Paste")
			(net "GND")
		)
		(pad "5" smd rect
			(at 0.97536 -1.6256)
			(size 0.3556 1.524)
			(layers "F.Cu" "F.Mask" "F.Paste")
			(net "CPU_U192_PIN5_RX")
		)
		(pad "6" smd rect
			(at 0.32512 -1.6256)
			(size 0.3556 1.524)
			(layers "F.Cu" "F.Mask" "F.Paste")
			(net "CPU_U192_PIN6_TX")
		)
		(pad "7" smd rect
			(at -0.32512 -1.6256)
			(size 0.3556 1.524)
			(layers "F.Cu" "F.Mask" "F.Paste")
			(net "DEBUG_OE_1_N")
		)
		(pad "8" smd rect
			(at -0.97536 -1.6256)
			(size 0.3556 1.524)
			(layers "F.Cu" "F.Mask" "F.Paste")
			(net "P3V3_STBY")
		)
	)
	(footprint ""
		(layer "F.Cu")
		(at 35.383216 -203.12888 90)
		(property "Reference" "R566"
			(at 0 0 90)
			(layer "F.SilkS")
			(hide yes)
			(effects
				(font
					(size 1.27 1.27)
				)
			)
		)
		(property "Value" "0R2J-2-GP"
			(at 0.064008 -3.993896 90)
			(unlocked yes)
			(layer "F.Fab")
			(hide yes)
			(effects
				(font
					(size 1.016 1.016)
					(thickness 0.1524)
				)
			)
		)
		(property "Device Type" "R402H16"
			(at 0.064008 -5.517896 90)
			(unlocked yes)
			(layer "F.Fab")
			(hide yes)
			(effects
				(font
					(size 1.016 1.016)
					(thickness 0.1524)
				)
			)
		)
		(duplicate_pad_numbers_are_jumpers no)
		(fp_line
			(start 0.508 -0.9398)
			(end -0.508 -0.9398)
			(stroke
				(width 0.1524)
				(type default)
			)
			(layer "F.SilkS")
		)
		(fp_line
			(start -0.508 -0.9398)
			(end -0.508 0.9398)
			(stroke
				(width 0.1524)
				(type default)
			)
			(layer "F.SilkS")
		)
		(fp_rect
			(start -0.508 0.9398)
			(end 0.508 -0.9398)
			(stroke
				(width 0)
				(type default)
			)
			(fill no)
			(layer "F.CrtYd")
		)
		(fp_rect
			(start -0.508 0.9398)
			(end 0.508 -0.9398)
			(stroke
				(width 0)
				(type default)
			)
			(fill no)
			(layer "F.Fab")
		)
		(pad "1" smd custom
			(at 0 -0.4445 90)
			(size 0.1397 0.1397)
			(layers "F.Cu" "F.Mask" "F.Paste")
			(net "VOL_SEN_SDA_U17")
			(options
				(clearance outline)
				(anchor circle)
			)
			(primitives
				(gr_poly
					(pts
						(arc
							(start -0.1778 -0.2794)
							(mid -0.249642 -0.249642)
							(end -0.2794 -0.1778)
						)
						(arc
							(start -0.2794 0.1778)
							(mid -0.249642 0.249642)
							(end -0.1778 0.2794)
						)
						(arc
							(start 0.1778 0.2794)
							(mid 0.249642 0.249642)
							(end 0.2794 0.1778)
						)
						(arc
							(start 0.2794 -0.1778)
							(mid 0.249642 -0.249642)
							(end 0.1778 -0.2794)
						)
					)
					(width 0)
					(fill yes)
				)
			)
		)
		(pad "2" smd custom
			(at 0 0.4445 90)
			(size 0.1397 0.1397)
			(layers "F.Cu" "F.Mask" "F.Paste")
			(net "BMC_I2C_A_SDA")
			(options
				(clearance outline)
				(anchor circle)
			)
			(primitives
				(gr_poly
					(pts
						(arc
							(start -0.1778 -0.2794)
							(mid -0.249642 -0.249642)
							(end -0.2794 -0.1778)
						)
						(arc
							(start -0.2794 0.1778)
							(mid -0.249642 0.249642)
							(end -0.1778 0.2794)
						)
						(arc
							(start 0.1778 0.2794)
							(mid 0.249642 0.249642)
							(end 0.2794 0.1778)
						)
						(arc
							(start 0.2794 -0.1778)
							(mid 0.249642 -0.249642)
							(end 0.1778 -0.2794)
						)
					)
					(width 0)
					(fill yes)
				)
			)
		)
	)
	(footprint ""
		(layer "F.Cu")
		(at 328.549 -118.491 180)
		(property "Reference" "PC22"
			(at 0 0 180)
			(layer "F.SilkS")
			(hide yes)
			(effects
				(font
					(size 1.27 1.27)
				)
			)
		)
		(property "Value" "SC22U25V5MX-GP"
			(at -0.0762 -6.1214 180)
			(unlocked yes)
			(layer "F.Fab")
			(hide yes)
			(effects
				(font
					(size 1.016 1.016)
					(thickness 0.1524)
				)
			)
		)
		(property "Device Type" "C805H58"
			(at -0.0762 -8.1534 180)
			(unlocked yes)
			(layer "F.Fab")
			(hide yes)
			(effects
				(font
					(size 1.016 1.016)
					(thickness 0.1524)
				)
			)
		)
		(duplicate_pad_numbers_are_jumpers no)
		(fp_line
			(start 0.635 0)
			(end -0.635 0)
			(stroke
				(width 0.508)
				(type default)
			)
			(layer "F.SilkS")
		)
		(fp_rect
			(start -0.9652 1.778)
			(end 0.9652 -1.778)
			(stroke
				(width 0)
				(type default)
			)
			(fill no)
			(layer "F.CrtYd")
		)
		(fp_poly
			(pts
				(xy -0.9652 -1.778) (xy 0.9652 -1.778) (xy 0.9652 1.778) (xy -0.9652 1.778)
			)
			(stroke
				(width 0)
				(type default)
			)
			(fill no)
			(layer "F.Fab")
		)
		(pad "1" smd rect
			(at 0 -0.9652 180)
			(size 1.397 1.143)
			(layers "F.Cu" "F.Mask" "F.Paste")
			(net "P3V3_STBY_VIN")
		)
		(pad "2" smd rect
			(at 0 0.9652 180)
			(size 1.397 1.143)
			(layers "F.Cu" "F.Mask" "F.Paste")
			(net "GND")
		)
	)
	(footprint ""
		(layer "F.Cu")
		(at 12.650216 -215.82888 90)
		(property "Reference" "SC564"
			(at 0 0 90)
			(layer "F.SilkS")
			(hide yes)
			(effects
				(font
					(size 1.27 1.27)
				)
			)
		)
		(property "Value" "SCD1U16V2KX-3GP"
			(at 1.1811 -2.7051 90)
			(unlocked yes)
			(layer "F.Fab")
			(hide yes)
			(effects
				(font
					(size 1.016 1.016)
					(thickness 0.1524)
				)
			)
		)
		(property "Device Type" "C402H22"
			(at 1.1811 -4.2291 90)
			(unlocked yes)
			(layer "F.Fab")
			(hide yes)
			(effects
				(font
					(size 1.016 1.016)
					(thickness 0.1524)
				)
			)
		)
		(duplicate_pad_numbers_are_jumpers no)
		(fp_rect
			(start -0.4318 0.9525)
			(end 0.4318 -0.9525)
			(stroke
				(width 0)
				(type default)
			)
			(fill no)
			(layer "F.CrtYd")
		)
		(fp_rect
			(start -0.4318 0.9525)
			(end 0.4318 -0.9525)
			(stroke
				(width 0)
				(type default)
			)
			(fill no)
			(layer "F.Fab")
		)
		(pad "1" smd custom
			(at 0 -0.4445 90)
			(size 0.1524 0.1524)
			(layers "F.Cu" "F.Mask" "F.Paste")
			(net "P3V3_STBY")
			(options
				(clearance outline)
				(anchor circle)
			)
			(primitives
				(gr_poly
					(pts
						(arc
							(start 0.3048 -0.2032)
							(mid 0.275042 -0.275042)
							(end 0.2032 -0.3048)
						)
						(arc
							(start -0.2032 -0.3048)
							(mid -0.275042 -0.275042)
							(end -0.3048 -0.2032)
						)
						(arc
							(start -0.3048 0.2032)
							(mid -0.275042 0.275042)
							(end -0.2032 0.3048)
						)
						(arc
							(start 0.2032 0.3048)
							(mid 0.275042 0.275042)
							(end 0.3048 0.2032)
						)
					)
					(width 0)
					(fill yes)
				)
			)
		)
		(pad "2" smd custom
			(at 0 0.4445 90)
			(size 0.1524 0.1524)
			(layers "F.Cu" "F.Mask" "F.Paste")
			(net "GND")
			(options
				(clearance outline)
				(anchor circle)
			)
			(primitives
				(gr_poly
					(pts
						(arc
							(start 0.3048 -0.2032)
							(mid 0.275042 -0.275042)
							(end 0.2032 -0.3048)
						)
						(arc
							(start -0.2032 -0.3048)
							(mid -0.275042 -0.275042)
							(end -0.3048 -0.2032)
						)
						(arc
							(start -0.3048 0.2032)
							(mid -0.275042 0.275042)
							(end -0.2032 0.3048)
						)
						(arc
							(start 0.2032 0.3048)
							(mid 0.275042 0.275042)
							(end 0.3048 0.2032)
						)
					)
					(width 0)
					(fill yes)
				)
			)
		)
	)
	(footprint ""
		(layer "F.Cu")
		(at 14.682216 -222.94088 -90)
		(property "Reference" "SR297"
			(at 0 0 270)
			(layer "F.SilkS")
			(hide yes)
			(effects
				(font
					(size 1.27 1.27)
				)
			)
		)
		(property "Value" "0R2J-2-GP"
			(at 0.064008 -3.993896 270)
			(unlocked yes)
			(layer "F.Fab")
			(hide yes)
			(effects
				(font
					(size 1.016 1.016)
					(thickness 0.1524)
				)
			)
		)
		(property "Device Type" "R402H16"
			(at 0.064008 -5.517896 270)
			(unlocked yes)
			(layer "F.Fab")
			(hide yes)
			(effects
				(font
					(size 1.016 1.016)
					(thickness 0.1524)
				)
			)
		)
		(duplicate_pad_numbers_are_jumpers no)
		(fp_line
			(start -0.508 -0.9398)
			(end -0.508 0.9398)
			(stroke
				(width 0.1524)
				(type default)
			)
			(layer "F.SilkS")
		)
		(fp_line
			(start 0.508 -0.9398)
			(end -0.508 -0.9398)
			(stroke
				(width 0.1524)
				(type default)
			)
			(layer "F.SilkS")
		)
		(fp_rect
			(start -0.508 0.9398)
			(end 0.508 -0.9398)
			(stroke
				(width 0)
				(type default)
			)
			(fill no)
			(layer "F.CrtYd")
		)
		(fp_rect
			(start -0.508 0.9398)
			(end 0.508 -0.9398)
			(stroke
				(width 0)
				(type default)
			)
			(fill no)
			(layer "F.Fab")
		)
		(pad "1" smd custom
			(at 0 -0.4445 270)
			(size 0.1397 0.1397)
			(layers "F.Cu" "F.Mask" "F.Paste")
			(net "PWR_SCL")
			(options
				(clearance outline)
				(anchor circle)
			)
			(primitives
				(gr_poly
					(pts
						(arc
							(start -0.1778 -0.2794)
							(mid -0.249642 -0.249642)
							(end -0.2794 -0.1778)
						)
						(arc
							(start -0.2794 0.1778)
							(mid -0.249642 0.249642)
							(end -0.1778 0.2794)
						)
						(arc
							(start 0.1778 0.2794)
							(mid 0.249642 0.249642)
							(end 0.2794 0.1778)
						)
						(arc
							(start 0.2794 -0.1778)
							(mid 0.249642 -0.249642)
							(end 0.1778 -0.2794)
						)
					)
					(width 0)
					(fill yes)
				)
			)
		)
		(pad "2" smd custom
			(at 0 0.4445 270)
			(size 0.1397 0.1397)
			(layers "F.Cu" "F.Mask" "F.Paste")
			(net "EXP_SCL_0")
			(options
				(clearance outline)
				(anchor circle)
			)
			(primitives
				(gr_poly
					(pts
						(arc
							(start -0.1778 -0.2794)
							(mid -0.249642 -0.249642)
							(end -0.2794 -0.1778)
						)
						(arc
							(start -0.2794 0.1778)
							(mid -0.249642 0.249642)
							(end -0.1778 0.2794)
						)
						(arc
							(start 0.1778 0.2794)
							(mid 0.249642 0.249642)
							(end 0.2794 0.1778)
						)
						(arc
							(start 0.2794 -0.1778)
							(mid 0.249642 -0.249642)
							(end 0.1778 -0.2794)
						)
					)
					(width 0)
					(fill yes)
				)
			)
		)
	)
	(footprint ""
		(layer "F.Cu")
		(at 264.541 -28.194 -90)
		(property "Reference" "PC56"
			(at 0 0 270)
			(layer "F.SilkS")
			(hide yes)
			(effects
				(font
					(size 1.27 1.27)
				)
			)
		)
		(property "Value" "SC22U6D3V3MX-1-GP"
			(at 0 -2.8194 270)
			(unlocked yes)
			(layer "F.Fab")
			(hide yes)
			(effects
				(font
					(size 1.016 1.016)
					(thickness 0.1524)
				)
			)
		)
		(property "Device Type" "C603H40"
			(at 0 -4.3434 270)
			(unlocked yes)
			(layer "F.Fab")
			(hide yes)
			(effects
				(font
					(size 1.016 1.016)
					(thickness 0.1524)
				)
			)
		)
		(duplicate_pad_numbers_are_jumpers no)
		(fp_line
			(start 0.508 0)
			(end -0.508 0)
			(stroke
				(width 0.2032)
				(type default)
			)
			(layer "F.SilkS")
		)
		(fp_rect
			(start -0.5842 1.3335)
			(end 0.5842 -1.3335)
			(stroke
				(width 0)
				(type default)
			)
			(fill no)
			(layer "F.CrtYd")
		)
		(fp_rect
			(start -0.5842 1.3335)
			(end 0.5842 -1.3335)
			(stroke
				(width 0)
				(type default)
			)
			(fill no)
			(layer "F.Fab")
		)
		(pad "1" smd custom
			(at 0 -0.762 270)
			(size 0.2159 0.2159)
			(layers "F.Cu" "F.Mask" "F.Paste")
			(net "P1V8_STBY")
			(options
				(clearance outline)
				(anchor circle)
			)
			(primitives
				(gr_poly
					(pts
						(arc
							(start -0.3302 -0.4318)
							(mid -0.402042 -0.402042)
							(end -0.4318 -0.3302)
						)
						(arc
							(start -0.4318 0.3302)
							(mid -0.402042 0.402042)
							(end -0.3302 0.4318)
						)
						(arc
							(start 0.3302 0.4318)
							(mid 0.402042 0.402042)
							(end 0.4318 0.3302)
						)
						(arc
							(start 0.4318 -0.3302)
							(mid 0.402042 -0.402042)
							(end 0.3302 -0.4318)
						)
					)
					(width 0)
					(fill yes)
				)
			)
		)
		(pad "2" smd custom
			(at 0 0.762 270)
			(size 0.2159 0.2159)
			(layers "F.Cu" "F.Mask" "F.Paste")
			(net "GND")
			(options
				(clearance outline)
				(anchor circle)
			)
			(primitives
				(gr_poly
					(pts
						(arc
							(start -0.3302 -0.4318)
							(mid -0.402042 -0.402042)
							(end -0.4318 -0.3302)
						)
						(arc
							(start -0.4318 0.3302)
							(mid -0.402042 0.402042)
							(end -0.3302 0.4318)
						)
						(arc
							(start 0.3302 0.4318)
							(mid 0.402042 0.402042)
							(end 0.4318 0.3302)
						)
						(arc
							(start 0.4318 -0.3302)
							(mid 0.402042 -0.402042)
							(end 0.3302 -0.4318)
						)
					)
					(width 0)
					(fill yes)
				)
			)
		)
	)
	(footprint ""
		(layer "F.Cu")
		(at 341.786718 -139.804648 -90)
		(property "Reference" "X11"
			(at 0 0 270)
			(layer "F.SilkS")
			(hide yes)
			(effects
				(font
					(size 1.27 1.27)
				)
			)
		)
		(property "Value" "XTAL-24MHZ-87-GP"
			(at -0.0889 -3.0988 270)
			(unlocked yes)
			(layer "F.Fab")
			(hide yes)
			(effects
				(font
					(size 1.016 1.016)
					(thickness 0.1524)
				)
			)
		)
		(property "Device Type" "OSC-3225-4P-4H30"
			(at -0.0889 -4.6228 270)
			(unlocked yes)
			(layer "F.Fab")
			(hide yes)
			(effects
				(font
					(size 1.016 1.016)
					(thickness 0.1524)
				)
			)
		)
		(duplicate_pad_numbers_are_jumpers no)
		(fp_line
			(start -2.2098 1.651)
			(end -2.2098 0.6604)
			(stroke
				(width 0.3302)
				(type default)
			)
			(layer "F.SilkS")
		)
		(fp_line
			(start -1.143 1.651)
			(end -2.2098 1.651)
			(stroke
				(width 0.3302)
				(type default)
			)
			(layer "F.SilkS")
		)
		(fp_line
			(start -2.1209 1.5494)
			(end 2.1209 1.5494)
			(stroke
				(width 0.1524)
				(type default)
			)
			(layer "F.SilkS")
		)
		(fp_line
			(start 2.1209 1.5494)
			(end 2.1209 -1.5494)
			(stroke
				(width 0.1524)
				(type default)
			)
			(layer "F.SilkS")
		)
		(fp_line
			(start -2.1209 -1.5494)
			(end -2.1209 1.5494)
			(stroke
				(width 0.1524)
				(type default)
			)
			(layer "F.SilkS")
		)
		(fp_line
			(start 2.1209 -1.5494)
			(end -2.1209 -1.5494)
			(stroke
				(width 0.1524)
				(type default)
			)
			(layer "F.SilkS")
		)
		(fp_poly
			(pts
				(xy -2.6289 1.1938) (xy -2.6289 0.3302) (xy -2.1971 0.762)
			)
			(stroke
				(width 0)
				(type default)
			)
			(fill yes)
			(layer "F.SilkS")
		)
		(fp_rect
			(start -1.6002 1.2446)
			(end 1.6002 -1.2446)
			(stroke
				(width 0)
				(type default)
			)
			(fill no)
			(layer "F.CrtYd")
		)
		(fp_poly
			(pts
				(xy -2.3749 1.8034) (xy -2.3749 -1.8034) (xy 2.3749 -1.8034) (xy 2.3749 1.8034) (xy 0.00254 1.8034)
				(xy 0.00254 1.2446) (xy 1.6002 1.2446) (xy 1.6002 -1.2446) (xy -1.6002 -1.2446) (xy -1.6002 1.2446)
				(xy -0.00254 1.2446) (xy -0.00254 1.8034)
			)
			(stroke
				(width 0)
				(type default)
			)
			(fill no)
			(layer "F.CrtYd")
		)
		(fp_rect
			(start -2.3749 1.8034)
			(end 2.3749 -1.8034)
			(stroke
				(width 0)
				(type default)
			)
			(fill no)
			(layer "F.Fab")
		)
		(pad "1" smd rect
			(at -1.171448 0.756412 270)
			(size 1.397 1.0668)
			(layers "F.Cu" "F.Mask" "F.Paste")
			(net "USB_HUB_XTAL_OUT")
		)
		(pad "2" smd rect
			(at 1.171448 0.756412 270)
			(size 1.397 1.0668)
			(layers "F.Cu" "F.Mask" "F.Paste")
			(net "GND")
		)
		(pad "3" smd rect
			(at 1.171448 -0.756412 270)
			(size 1.397 1.0668)
			(layers "F.Cu" "F.Mask" "F.Paste")
			(net "USB_HUB_XTAL_IN")
		)
		(pad "4" smd rect
			(at -1.171448 -0.756412 270)
			(size 1.397 1.0668)
			(layers "F.Cu" "F.Mask" "F.Paste")
			(net "GND")
		)
		(zone
			(layer "F.Cu")
			(hatch none 0.5)
			(connect_pads
				(clearance 0)
			)
			(min_thickness 0.25)
			(keepout
				(tracks not_allowed)
				(vias allowed)
				(pads allowed)
				(copperpour not_allowed)
				(footprints allowed)
			)
			(placement
				(enabled no)
				(sheetname "")
			)
			(fill
				(thermal_gap 0.5)
				(thermal_bridge_width 0.5)
				(island_removal_mode 0)
			)
			(polygon
				(pts
					(xy 341.735918 -139.855448) (xy 341.735918 -139.753848) (xy 341.837518 -139.753848) (xy 341.837518 -139.855448)
				)
			)
		)
		(zone
			(layer "F.Cu")
			(hatch none 0.5)
			(connect_pads
				(clearance 0)
			)
			(min_thickness 0.25)
			(keepout
				(tracks allowed)
				(vias not_allowed)
				(pads allowed)
				(copperpour not_allowed)
				(footprints allowed)
			)
			(placement
				(enabled no)
				(sheetname "")
			)
			(fill
				(thermal_gap 0.5)
				(thermal_bridge_width 0.5)
				(island_removal_mode 0)
			)
			(polygon
				(pts
					(xy 343.07653 -140.277596) (xy 343.07653 -139.3317) (xy 342.00973 -139.3317) (xy 342.00973 -137.9347)
					(xy 341.563706 -137.9347) (xy 341.563706 -139.3317) (xy 340.496906 -139.3317) (xy 340.496906 -140.277596)
					(xy 341.563706 -140.277596) (xy 341.563706 -141.674596) (xy 342.00973 -141.674596) (xy 342.00973 -140.277596)
				)
			)
		)
	)
)
